(kicad_pcb
	(version 20241229)
	(generator "pcbnew")
	(generator_version "9.0")
	(general
		(thickness 1.711)
		(legacy_teardrops no)
	)
	(paper "A4")
	(title_block
		(title "Antmicro Baseboard for Jetson AGX Thor")
		(date "2026-02-18")
		(rev "1.1.0")
		(company "Antmicro Ltd")
		(comment 1 "www.antmicro.com")
		(comment 9 "footprints 995-999 of 1170")
	)
	(layers
		(0 "F.Cu" signal)
		(4 "In1.Cu" signal)
		(6 "In2.Cu" signal)
		(8 "In3.Cu" signal)
		(10 "In4.Cu" jumper)
		(12 "In5.Cu" signal)
		(14 "In6.Cu" signal)
		(16 "In7.Cu" signal)
		(18 "In8.Cu" signal)
		(2 "B.Cu" signal)
		(9 "F.Adhes" user "F.Adhesive")
		(11 "B.Adhes" user "B.Adhesive")
		(13 "F.Paste" user)
		(15 "B.Paste" user)
		(5 "F.SilkS" user "F.Silkscreen")
		(7 "B.SilkS" user "B.Silkscreen")
		(1 "F.Mask" user)
		(3 "B.Mask" user)
		(17 "Dwgs.User" user "User.Drawings")
		(19 "Cmts.User" user "User.Comments")
		(21 "Eco1.User" user "User.Eco1")
		(23 "Eco2.User" user "User.Eco2")
		(25 "Edge.Cuts" user)
		(27 "Margin" user)
		(31 "F.CrtYd" user "F.Courtyard")
		(29 "B.CrtYd" user "B.Courtyard")
		(35 "F.Fab" user)
		(33 "B.Fab" user)
	)
	(footprint "antmicro-footprints:R_0402_1005Metric"
		(layer "B.Cu")
		(at 148.723313 149.115 90)
		(descr "Resistor SMD 0402")
		(tags "resistor SMD 0402")
		(property "Reference" "R6"
			(at -0.685 0.676687 90)
			(layer "B.SilkS")
			(effects
				(font
					(size 0.7 0.7)
					(thickness 0.15)
				)
				(justify right top mirror)
			)
		)
		(property "Value" "R_2k2_0402"
			(at -1.011843 -1.772046 90)
			(layer "B.Fab")
			(effects
				(font
					(size 0.7 0.7)
					(thickness 0.15)
				)
				(justify right top mirror)
			)
		)
		(property "Datasheet" "https://www.bourns.com/docs/product-datasheets/cr.pdf"
			(at 0 0 90)
			(layer "B.Fab")
			(hide yes)
			(effects
				(font
					(size 1.27 1.27)
					(thickness 0.15)
				)
				(justify mirror)
			)
		)
		(property "Description" "SMD Chip Resistor, 2.2 kohm, ± 1%, 62.5 mW, 0402 [1005 Metric], Thick Film, General Purpose"
			(at 0 0 90)
			(layer "B.Fab")
			(hide yes)
			(effects
				(font
					(size 1.27 1.27)
					(thickness 0.15)
				)
				(justify mirror)
			)
		)
		(property "Manufacturer" "Bourns"
			(at 0 0 270)
			(unlocked yes)
			(layer "B.Fab")
			(hide yes)
			(effects
				(font
					(size 1 1)
					(thickness 0.15)
				)
				(justify mirror)
			)
		)
		(property "MPN" "CR0402-FX-2201GLF"
			(at 0 0 270)
			(unlocked yes)
			(layer "B.Fab")
			(hide yes)
			(effects
				(font
					(size 1 1)
					(thickness 0.15)
				)
				(justify mirror)
			)
		)
		(property "Val" "2k2"
			(at 0 0 270)
			(unlocked yes)
			(layer "B.Fab")
			(hide yes)
			(effects
				(font
					(size 1 1)
					(thickness 0.15)
				)
				(justify mirror)
			)
		)
		(property "License" "Apache-2.0"
			(at 0 0 270)
			(unlocked yes)
			(layer "B.Fab")
			(hide yes)
			(effects
				(font
					(size 1 1)
					(thickness 0.15)
				)
				(justify mirror)
			)
		)
		(property "Author" "Antmicro"
			(at 0 0 270)
			(unlocked yes)
			(layer "B.Fab")
			(hide yes)
			(effects
				(font
					(size 1 1)
					(thickness 0.15)
				)
				(justify mirror)
			)
		)
		(property "Tolerance" "1%"
			(at 0 0 270)
			(unlocked yes)
			(layer "B.Fab")
			(hide yes)
			(effects
				(font
					(size 1 1)
					(thickness 0.15)
				)
				(justify mirror)
			)
		)
		(sheetname "/SoM_Power/")
		(sheetfile "som_power.kicad_sch")
		(attr smd)
		(fp_poly
			(pts
				(xy -0.925 0.47) (xy -0.925 -0.47) (xy 0.925 -0.47) (xy 0.925 0.47)
			)
			(stroke
				(width 0.05)
				(type default)
			)
			(fill no)
			(layer "B.CrtYd")
		)
		(fp_poly
			(pts
				(xy -0.5 0.25) (xy -0.5 -0.25) (xy 0.5 -0.25) (xy 0.5 0.25)
			)
			(stroke
				(width 0.15)
				(type solid)
			)
			(fill no)
			(layer "B.Fab")
		)
		(fp_text user "Author: Antmicro"
			(at -0.95 -4.169 90)
			(layer "B.Fab")
			(effects
				(font
					(size 0.7 0.7)
					(thickness 0.15)
				)
				(justify right top mirror)
			)
		)
		(fp_text user "${REFERENCE}"
			(at -0.95 -3.168 90)
			(layer "B.Fab")
			(effects
				(font
					(size 0.7 0.7)
					(thickness 0.15)
				)
				(justify right top mirror)
			)
		)
		(fp_text user "License: Apache-2.0"
			(at -0.949999 -5.169 90)
			(layer "B.Fab")
			(effects
				(font
					(size 0.7 0.7)
					(thickness 0.15)
				)
				(justify right top mirror)
			)
		)
		(pad "1" smd roundrect
			(at -0.48 0 90)
			(size 0.59 0.64)
			(layers "B.Cu" "B.Mask" "B.Paste")
			(roundrect_rratio 0.25)
			(net 10 "Net-(BT1-+)")
			(pintype "passive")
		)
		(pad "2" smd roundrect
			(at 0.48 0 90)
			(size 0.59 0.64)
			(layers "B.Cu" "B.Mask" "B.Paste")
			(roundrect_rratio 0.25)
			(net 32 "Net-(D1-C)")
			(pintype "passive")
		)
	)
	(footprint "antmicro-footprints:R_0402_1005Metric"
		(layer "B.Cu")
		(at 71.1 65.3)
		(descr "Resistor SMD 0402")
		(tags "resistor SMD 0402")
		(property "Reference" "R397"
			(at 0.9 -0.3 0)
			(layer "B.SilkS")
			(effects
				(font
					(size 0.7 0.7)
					(thickness 0.15)
				)
				(justify right top mirror)
			)
		)
		(property "Value" "R_0R_0402"
			(at -1.011843 -1.772047 0)
			(layer "B.Fab")
			(effects
				(font
					(size 0.7 0.7)
					(thickness 0.15)
				)
				(justify right top mirror)
			)
		)
		(property "Datasheet" "https://industrial.panasonic.com/cdbs/www-data/pdf/RDA0000/AOA0000C301.pdf"
			(at 0 0 0)
			(layer "B.Fab")
			(hide yes)
			(effects
				(font
					(size 1.27 1.27)
					(thickness 0.15)
				)
				(justify mirror)
			)
		)
		(property "Description" "SMD Chip Resistor, Jumper, 0 ohm, 100 mW, 0402 [1005 Metric], Thick Film, General Purpose"
			(at 0 0 0)
			(layer "B.Fab")
			(hide yes)
			(effects
				(font
					(size 1.27 1.27)
					(thickness 0.15)
				)
				(justify mirror)
			)
		)
		(property "MPN" "ERJ2GE0R00X"
			(at 0 0 180)
			(unlocked yes)
			(layer "B.Fab")
			(hide yes)
			(effects
				(font
					(size 1 1)
					(thickness 0.15)
				)
				(justify mirror)
			)
		)
		(property "Manufacturer" "Panasonic"
			(at 0 0 180)
			(unlocked yes)
			(layer "B.Fab")
			(hide yes)
			(effects
				(font
					(size 1 1)
					(thickness 0.15)
				)
				(justify mirror)
			)
		)
		(property "License" "Apache-2.0"
			(at 0 0 180)
			(unlocked yes)
			(layer "B.Fab")
			(hide yes)
			(effects
				(font
					(size 1 1)
					(thickness 0.15)
				)
				(justify mirror)
			)
		)
		(property "Author" "Antmicro"
			(at 0 0 180)
			(unlocked yes)
			(layer "B.Fab")
			(hide yes)
			(effects
				(font
					(size 1 1)
					(thickness 0.15)
				)
				(justify mirror)
			)
		)
		(property "Val" "0R"
			(at 0 0 180)
			(unlocked yes)
			(layer "B.Fab")
			(hide yes)
			(effects
				(font
					(size 1 1)
					(thickness 0.15)
				)
				(justify mirror)
			)
		)
		(property "Tolerance" "~"
			(at 0 0 180)
			(unlocked yes)
			(layer "B.Fab")
			(hide yes)
			(effects
				(font
					(size 1 1)
					(thickness 0.15)
				)
				(justify mirror)
			)
		)
		(property "Current" "1A"
			(at 0 0 180)
			(unlocked yes)
			(layer "B.Fab")
			(hide yes)
			(effects
				(font
					(size 1 1)
					(thickness 0.15)
				)
				(justify mirror)
			)
		)
		(sheetname "/CSI/")
		(sheetfile "csi.kicad_sch")
		(attr smd)
		(fp_rect
			(start -0.925 0.47)
			(end 0.925 -0.47)
			(stroke
				(width 0.05)
				(type default)
			)
			(fill no)
			(layer "B.CrtYd")
		)
		(fp_rect
			(start -0.5 0.25)
			(end 0.5 -0.25)
			(stroke
				(width 0.15)
				(type solid)
			)
			(fill no)
			(layer "B.Fab")
		)
		(fp_text user "${REFERENCE}"
			(at -0.95 -3.168 0)
			(layer "B.Fab")
			(effects
				(font
					(size 0.7 0.7)
					(thickness 0.15)
				)
				(justify right top mirror)
			)
		)
		(fp_text user "Author: Antmicro"
			(at -0.95 -4.169 0)
			(layer "B.Fab")
			(effects
				(font
					(size 0.7 0.7)
					(thickness 0.15)
				)
				(justify right top mirror)
			)
		)
		(fp_text user "License: Apache-2.0"
			(at -0.95 -5.169 0)
			(layer "B.Fab")
			(effects
				(font
					(size 0.7 0.7)
					(thickness 0.15)
				)
				(justify right top mirror)
			)
		)
		(pad "1" smd roundrect
			(at -0.48 0)
			(size 0.59 0.64)
			(layers "B.Cu" "B.Mask" "B.Paste")
			(roundrect_rratio 0.25)
			(net 991 "/CSI/SDA_CAM3")
			(pintype "passive")
		)
		(pad "2" smd roundrect
			(at 0.48 0)
			(size 0.59 0.64)
			(layers "B.Cu" "B.Mask" "B.Paste")
			(roundrect_rratio 0.25)
			(net 937 "Net-(J10-Pad41)")
			(pintype "passive")
		)
	)
	(footprint "antmicro-footprints:LED_0603_1608Metric_G"
		(layer "B.Cu")
		(at 226 54.75 180)
		(descr "LED SMD 0603 Green")
		(tags "LED SMD 0603 Green")
		(property "Reference" "D26"
			(at -3.5 -0.37 0)
			(layer "B.SilkS")
			(effects
				(font
					(size 0.7 0.7)
					(thickness 0.15)
				)
				(justify left bottom mirror)
			)
		)
		(property "Value" "LED_G_0603_LTST-C190GKT"
			(at -0.001 -1.599 0)
			(layer "B.Fab")
			(effects
				(font
					(size 0.7 0.7)
					(thickness 0.15)
				)
				(justify left bottom mirror)
			)
		)
		(property "Datasheet" "https://media.digikey.com/pdf/Data%20Sheets/Lite-On%20PDFs/LTST-C190GKT.pdf"
			(at 0 0 0)
			(layer "B.Fab")
			(hide yes)
			(effects
				(font
					(size 1.27 1.27)
					(thickness 0.15)
				)
				(justify mirror)
			)
		)
		(property "Description" "LED, Green, SMD, 0603, 20 mA, 2.1 V, 569 nm"
			(at 0 0 0)
			(layer "B.Fab")
			(hide yes)
			(effects
				(font
					(size 1.27 1.27)
					(thickness 0.15)
				)
				(justify mirror)
			)
		)
		(property "MPN" "LTST-C190GKT"
			(at 0 0 0)
			(unlocked yes)
			(layer "B.Fab")
			(hide yes)
			(effects
				(font
					(size 1 1)
					(thickness 0.15)
				)
				(justify mirror)
			)
		)
		(property "Manufacturer" "Lite-On"
			(at 0 0 0)
			(unlocked yes)
			(layer "B.Fab")
			(hide yes)
			(effects
				(font
					(size 1 1)
					(thickness 0.15)
				)
				(justify mirror)
			)
		)
		(property "Author" "Antmicro"
			(at 0 0 0)
			(unlocked yes)
			(layer "B.Fab")
			(hide yes)
			(effects
				(font
					(size 1 1)
					(thickness 0.15)
				)
				(justify mirror)
			)
		)
		(property "License" "Apache-2.0"
			(at 0 0 0)
			(unlocked yes)
			(layer "B.Fab")
			(hide yes)
			(effects
				(font
					(size 1 1)
					(thickness 0.15)
				)
				(justify mirror)
			)
		)
		(property "Color" "Green"
			(at 0 0 0)
			(unlocked yes)
			(layer "B.Fab")
			(hide yes)
			(effects
				(font
					(size 1 1)
					(thickness 0.15)
				)
				(justify mirror)
			)
		)
		(sheetname "/CSI/")
		(sheetfile "csi.kicad_sch")
		(attr smd)
		(fp_line
			(start 0.22 0.35)
			(end -0.22 0.35)
			(stroke
				(width 0.15)
				(type solid)
			)
			(layer "B.SilkS")
		)
		(fp_line
			(start 0.22 -0.35)
			(end -0.22 -0.35)
			(stroke
				(width 0.15)
				(type solid)
			)
			(layer "B.SilkS")
		)
		(fp_line
			(start 0.105328 -0.001008)
			(end 0.240001 -0.001)
			(stroke
				(width 0.1)
				(type solid)
			)
			(layer "B.SilkS")
		)
		(fp_line
			(start 0.105328 -0.201008)
			(end 0.105329 0.198992)
			(stroke
				(width 0.1)
				(type solid)
			)
			(layer "B.SilkS")
		)
		(fp_line
			(start 0.105328 -0.201008)
			(end -0.094672 -0.001008)
			(stroke
				(width 0.1)
				(type solid)
			)
			(layer "B.SilkS")
		)
		(fp_line
			(start -0.094672 -0.001008)
			(end 0.105329 0.198992)
			(stroke
				(width 0.1)
				(type solid)
			)
			(layer "B.SilkS")
		)
		(fp_line
			(start -0.094672 -0.001008)
			(end -0.24 -0.001008)
			(stroke
				(width 0.1)
				(type solid)
			)
			(layer "B.SilkS")
		)
		(fp_line
			(start -0.094672 -0.201008)
			(end -0.094672 0.198992)
			(stroke
				(width 0.1)
				(type solid)
			)
			(layer "B.SilkS")
		)
		(fp_line
			(start -1.18 0.319)
			(end -1.18 -0.321)
			(stroke
				(width 0.15)
				(type solid)
			)
			(layer "B.SilkS")
		)
		(fp_poly
			(pts
				(xy 1.25 -0.65) (xy 1.25 0.65) (xy -1.25 0.65) (xy -1.25 -0.65)
			)
			(stroke
				(width 0.05)
				(type solid)
			)
			(fill no)
			(layer "B.CrtYd")
		)
		(fp_line
			(start 0.599 0)
			(end 0.200999 0)
			(stroke
				(width 0.15)
				(type solid)
			)
			(layer "B.Fab")
		)
		(fp_line
			(start 0.201 0.202)
			(end -0.101 0)
			(stroke
				(width 0.15)
				(type solid)
			)
			(layer "B.Fab")
		)
		(fp_line
			(start 0.201 -0.2)
			(end 0.200999 0)
			(stroke
				(width 0.15)
				(type solid)
			)
			(layer "B.Fab")
		)
		(fp_line
			(start 0.200999 0)
			(end 0.201 0.202)
			(stroke
				(width 0.15)
				(type solid)
			)
			(layer "B.Fab")
		)
		(fp_line
			(start -0.101 0)
			(end 0.201 -0.2)
			(stroke
				(width 0.15)
				(type solid)
			)
			(layer "B.Fab")
		)
		(fp_line
			(start -0.199 0.202)
			(end -0.199 -0.1)
			(stroke
				(width 0.15)
				(type solid)
			)
			(layer "B.Fab")
		)
		(fp_line
			(start -0.199 0)
			(end -0.597 0)
			(stroke
				(width 0.15)
				(type solid)
			)
			(layer "B.Fab")
		)
		(fp_line
			(start -0.199 -0.2)
			(end -0.199 -0.1)
			(stroke
				(width 0.15)
				(type solid)
			)
			(layer "B.Fab")
		)
		(fp_poly
			(pts
				(xy 0.848 -0.4) (xy 0.848 0.401999) (xy -0.85 0.402) (xy -0.85 -0.4)
			)
			(stroke
				(width 0.15)
				(type solid)
			)
			(fill no)
			(layer "B.Fab")
		)
		(fp_text user "Author: Antmicro"
			(at -1.4224 -4.799 0)
			(layer "B.Fab")
			(effects
				(font
					(size 0.7 0.7)
					(thickness 0.15)
				)
				(justify left bottom mirror)
			)
		)
		(fp_text user "${REFERENCE}"
			(at -1.4224 -5.999 0)
			(layer "B.Fab")
			(effects
				(font
					(size 0.7 0.7)
					(thickness 0.15)
				)
				(justify left bottom mirror)
			)
		)
		(fp_text user "License: Apache-2.0"
			(at -1.4224 -3.599 0)
			(layer "B.Fab")
			(effects
				(font
					(size 0.7 0.7)
					(thickness 0.15)
				)
				(justify left bottom mirror)
			)
		)
		(pad "1" smd roundrect
			(at -0.7 0)
			(size 0.8 1)
			(layers "B.Cu" "B.Mask" "B.Paste")
			(roundrect_rratio 0.2)
			(net 1 "GND")
			(pinfunction "C")
			(pintype "passive")
		)
		(pad "2" smd roundrect
			(at 0.7 0)
			(size 0.8 1)
			(layers "B.Cu" "B.Mask" "B.Paste")
			(roundrect_rratio 0.2)
			(net 539 "Net-(D26-A)")
			(pinfunction "A")
			(pintype "passive")
		)
	)
	(footprint "antmicro-footprints:TP_SMD_0.75mm"
		(layer "B.Cu")
		(at 196.4 118.4 90)
		(property "Reference" "TP70"
			(at 0.4 -3.2 0)
			(layer "B.SilkS")
			(effects
				(font
					(size 0.7 0.7)
					(thickness 0.15)
				)
				(justify right top mirror)
			)
		)
		(property "Value" "TP_0.75mm_SMD"
			(at 0 -1.2 90)
			(layer "B.Fab")
			(effects
				(font
					(size 0.7 0.7)
					(thickness 0.15)
				)
				(justify right top mirror)
			)
		)
		(property "Description" "SMT test point"
			(at 0 0 90)
			(layer "B.Fab")
			(hide yes)
			(effects
				(font
					(size 1.27 1.27)
					(thickness 0.15)
				)
				(justify mirror)
			)
		)
		(property "MPN" ""
			(at 0 0 270)
			(unlocked yes)
			(layer "B.Fab")
			(hide yes)
			(effects
				(font
					(size 1 1)
					(thickness 0.15)
				)
				(justify mirror)
			)
		)
		(property "Manufacturer" ""
			(at 0 0 270)
			(unlocked yes)
			(layer "B.Fab")
			(hide yes)
			(effects
				(font
					(size 1 1)
					(thickness 0.15)
				)
				(justify mirror)
			)
		)
		(property "Author" "Antmicro"
			(at 0 0 270)
			(unlocked yes)
			(layer "B.Fab")
			(hide yes)
			(effects
				(font
					(size 1 1)
					(thickness 0.15)
				)
				(justify mirror)
			)
		)
		(property "License" "Apache-2.0"
			(at 0 0 270)
			(unlocked yes)
			(layer "B.Fab")
			(hide yes)
			(effects
				(font
					(size 1 1)
					(thickness 0.15)
				)
				(justify mirror)
			)
		)
		(sheetname "/USB Hub/")
		(sheetfile "usb_hub.kicad_sch")
		(attr exclude_from_pos_files exclude_from_bom)
		(fp_circle
			(center 0 0)
			(end 0.475 0)
			(stroke
				(width 0.05)
				(type default)
			)
			(fill no)
			(layer "B.CrtYd")
		)
		(fp_text user "${REFERENCE}"
			(at -0.4 -2.7 90)
			(layer "B.Fab")
			(effects
				(font
					(size 0.7 0.7)
					(thickness 0.15)
				)
				(justify right top mirror)
			)
		)
		(fp_text user "Author: Antmicro"
			(at -0.4 -3.901 90)
			(layer "B.Fab")
			(effects
				(font
					(size 0.7 0.7)
					(thickness 0.15)
				)
				(justify right top mirror)
			)
		)
		(fp_text user "License: Apache-2.0"
			(at -0.4 -5.101 90)
			(layer "B.Fab")
			(effects
				(font
					(size 0.7 0.7)
					(thickness 0.15)
				)
				(justify right top mirror)
			)
		)
		(pad "1" smd circle
			(at 0 0 90)
			(size 0.75 0.75)
			(layers "B.Cu" "B.Mask")
			(net 1106 "/USB Hub/DP2_VCONN2")
			(pinfunction "1")
			(pintype "passive")
		)
	)
	(footprint "antmicro-footprints:R_0402_1005Metric"
		(layer "B.Cu")
		(at 124.6 106.8 180)
		(descr "Resistor SMD 0402")
		(tags "resistor SMD 0402")
		(property "Reference" "R206"
			(at -3.9 -0.36 0)
			(layer "B.SilkS")
			(effects
				(font
					(size 0.7 0.7)
					(thickness 0.15)
				)
				(justify left bottom mirror)
			)
		)
		(property "Value" "R_0R_0402"
			(at -1.011843 -1.772046 0)
			(layer "B.Fab")
			(effects
				(font
					(size 0.7 0.7)
					(thickness 0.15)
				)
				(justify left bottom mirror)
			)
		)
		(property "Datasheet" "https://industrial.panasonic.com/cdbs/www-data/pdf/RDA0000/AOA0000C301.pdf"
			(at 0 0 0)
			(layer "B.Fab")
			(hide yes)
			(effects
				(font
					(size 1.27 1.27)
					(thickness 0.15)
				)
				(justify mirror)
			)
		)
		(property "Description" "SMD Chip Resistor, Jumper, 0 ohm, 100 mW, 0402 [1005 Metric], Thick Film, General Purpose"
			(at 0 0 0)
			(layer "B.Fab")
			(hide yes)
			(effects
				(font
					(size 1.27 1.27)
					(thickness 0.15)
				)
				(justify mirror)
			)
		)
		(property "MPN" "ERJ2GE0R00X"
			(at 0 0 0)
			(unlocked yes)
			(layer "B.Fab")
			(hide yes)
			(effects
				(font
					(size 1 1)
					(thickness 0.15)
				)
				(justify mirror)
			)
		)
		(property "Manufacturer" "Panasonic"
			(at 0 0 0)
			(unlocked yes)
			(layer "B.Fab")
			(hide yes)
			(effects
				(font
					(size 1 1)
					(thickness 0.15)
				)
				(justify mirror)
			)
		)
		(property "License" "Apache-2.0"
			(at 0 0 0)
			(unlocked yes)
			(layer "B.Fab")
			(hide yes)
			(effects
				(font
					(size 1 1)
					(thickness 0.15)
				)
				(justify mirror)
			)
		)
		(property "Author" "Antmicro"
			(at 0 0 0)
			(unlocked yes)
			(layer "B.Fab")
			(hide yes)
			(effects
				(font
					(size 1 1)
					(thickness 0.15)
				)
				(justify mirror)
			)
		)
		(property "Val" "0R"
			(at 0 0 0)
			(unlocked yes)
			(layer "B.Fab")
			(hide yes)
			(effects
				(font
					(size 1 1)
					(thickness 0.15)
				)
				(justify mirror)
			)
		)
		(property "Tolerance" "~"
			(at 0 0 0)
			(unlocked yes)
			(layer "B.Fab")
			(hide yes)
			(effects
				(font
					(size 1 1)
					(thickness 0.15)
				)
				(justify mirror)
			)
		)
		(property "Current" "1A"
			(at 0 0 0)
			(unlocked yes)
			(layer "B.Fab")
			(hide yes)
			(effects
				(font
					(size 1 1)
					(thickness 0.15)
				)
				(justify mirror)
			)
		)
		(sheetname "/M.2/")
		(sheetfile "m2.kicad_sch")
		(attr smd)
		(fp_poly
			(pts
				(xy -0.925 0.47) (xy 0.925 0.47) (xy 0.925 -0.47) (xy -0.925 -0.47)
			)
			(stroke
				(width 0.05)
				(type default)
			)
			(fill no)
			(layer "B.CrtYd")
		)
		(fp_poly
			(pts
				(xy -0.5 0.25) (xy 0.5 0.25) (xy 0.5 -0.25) (xy -0.5 -0.25)
			)
			(stroke
				(width 0.15)
				(type solid)
			)
			(fill no)
			(layer "B.Fab")
		)
		(fp_text user "Author: Antmicro"
			(at -0.95 -4.169 0)
			(layer "B.Fab")
			(effects
				(font
					(size 0.7 0.7)
					(thickness 0.15)
				)
				(justify left bottom mirror)
			)
		)
		(fp_text user "License: Apache-2.0"
			(at -0.949999 -5.169 0)
			(layer "B.Fab")
			(effects
				(font
					(size 0.7 0.7)
					(thickness 0.15)
				)
				(justify left bottom mirror)
			)
		)
		(fp_text user "${REFERENCE}"
			(at -0.95 -3.168 0)
			(layer "B.Fab")
			(effects
				(font
					(size 0.7 0.7)
					(thickness 0.15)
				)
				(justify left bottom mirror)
			)
		)
		(pad "1" smd roundrect
			(at -0.48 0 180)
			(size 0.59 0.64)
			(layers "B.Cu" "B.Mask" "B.Paste")
			(roundrect_rratio 0.25)
			(net 775 "/M.2/PCIe_{C5x4}.~{RST}")
			(pintype "passive")
		)
		(pad "2" smd roundrect
			(at 0.48 0 180)
			(size 0.59 0.64)
			(layers "B.Cu" "B.Mask" "B.Paste")
			(roundrect_rratio 0.25)
			(net 827 "/M.2/~{PERST_M}")
			(pintype "passive")
		)
	)
)
